(kicad_pcb
	(version 20241229)
	(generator "pcbnew")
	(generator_version "9.0")
	(general
		(thickness 1.6296)
		(legacy_teardrops no)
	)
	(paper "A3")
	(title_block
		(title "Thunderbolt to 10GbE adapter")
		(date "2026-04-21")
		(rev "1.1.0")
		(company "Antmicro Ltd")
		(comment 1 "www.antmicro.com")
		(comment 9 "footprints 578-582 of 703")
	)
	(layers
		(0 "F.Cu" signal)
		(4 "In1.Cu" signal)
		(6 "In2.Cu" signal)
		(8 "In3.Cu" signal)
		(10 "In4.Cu" signal)
		(12 "In5.Cu" signal)
		(14 "In6.Cu" signal)
		(2 "B.Cu" signal)
		(9 "F.Adhes" user "F.Adhesive")
		(11 "B.Adhes" user "B.Adhesive")
		(13 "F.Paste" user)
		(15 "B.Paste" user)
		(5 "F.SilkS" user "F.Silkscreen")
		(7 "B.SilkS" user "B.Silkscreen")
		(1 "F.Mask" user)
		(3 "B.Mask" user)
		(17 "Dwgs.User" user "User.Drawings")
		(19 "Cmts.User" user "User.Comments")
		(21 "Eco1.User" user "User.Eco1")
		(23 "Eco2.User" user "User.Eco2")
		(25 "Edge.Cuts" user)
		(27 "Margin" user)
		(31 "F.CrtYd" user "F.Courtyard")
		(29 "B.CrtYd" user "B.Courtyard")
		(35 "F.Fab" user)
		(33 "B.Fab" user)
	)
	(footprint "antmicro-footprints:C_0402_1005Metric"
		(layer "B.Cu")
		(at 181.25 136 180)
		(descr "Capacitor SMD 0402")
		(tags "capacitor SMD 0402")
		(property "Reference" "C297"
			(at -1.2 0.5 0)
			(layer "B.SilkS")
			(effects
				(font
					(size 0.7 0.7)
					(thickness 0.15)
				)
				(justify left bottom mirror)
			)
		)
		(property "Value" "C_1u_25V_0402"
			(at -1.022927 -2.155213 0)
			(layer "B.Fab")
			(effects
				(font
					(size 0.7 0.7)
					(thickness 0.15)
				)
				(justify left bottom mirror)
			)
		)
		(property "Datasheet" "https://www.murata.com/products/productdetail?partno=GRM155R61E105KE11%23"
			(at 0 0 0)
			(layer "B.Fab")
			(hide yes)
			(effects
				(font
					(size 1.27 1.27)
					(thickness 0.15)
				)
				(justify mirror)
			)
		)
		(property "Description" "SMD Multilayer Ceramic Capacitor, 1 µF, 25 V, 0402 [1005 Metric], ± 10%, X5R, GRM Series"
			(at 0 0 0)
			(layer "B.Fab")
			(hide yes)
			(effects
				(font
					(size 1.27 1.27)
					(thickness 0.15)
				)
				(justify mirror)
			)
		)
		(property "MPN" "GRM155R61E105KE11J"
			(at 0 0 180)
			(unlocked yes)
			(layer "B.Fab")
			(hide yes)
			(effects
				(font
					(size 1 1)
					(thickness 0.15)
				)
				(justify mirror)
			)
		)
		(property "Manufacturer" "Murata"
			(at 0 0 180)
			(unlocked yes)
			(layer "B.Fab")
			(hide yes)
			(effects
				(font
					(size 1 1)
					(thickness 0.15)
				)
				(justify mirror)
			)
		)
		(property "License" "Apache-2.0"
			(at 0 0 180)
			(unlocked yes)
			(layer "B.Fab")
			(hide yes)
			(effects
				(font
					(size 1 1)
					(thickness 0.15)
				)
				(justify mirror)
			)
		)
		(property "Author" "Antmicro"
			(at 0 0 180)
			(unlocked yes)
			(layer "B.Fab")
			(hide yes)
			(effects
				(font
					(size 1 1)
					(thickness 0.15)
				)
				(justify mirror)
			)
		)
		(property "Val" "1u"
			(at 0 0 180)
			(unlocked yes)
			(layer "B.Fab")
			(hide yes)
			(effects
				(font
					(size 1 1)
					(thickness 0.15)
				)
				(justify mirror)
			)
		)
		(property "Voltage" "25V"
			(at 0 0 180)
			(unlocked yes)
			(layer "B.Fab")
			(hide yes)
			(effects
				(font
					(size 1 1)
					(thickness 0.15)
				)
				(justify mirror)
			)
		)
		(property "Dielectric" "X5R"
			(at 0 0 180)
			(unlocked yes)
			(layer "B.Fab")
			(hide yes)
			(effects
				(font
					(size 1 1)
					(thickness 0.15)
				)
				(justify mirror)
			)
		)
		(sheetname "/2xRJ45/")
		(sheetfile "2xrj45.kicad_sch")
		(attr smd)
		(fp_rect
			(start -0.925 0.47)
			(end 0.925 -0.47)
			(stroke
				(width 0.05)
				(type default)
			)
			(fill no)
			(layer "B.CrtYd")
		)
		(fp_line
			(start 0.504 0.25)
			(end 0.504 -0.248)
			(stroke
				(width 0.15)
				(type solid)
			)
			(layer "B.Fab")
		)
		(fp_line
			(start 0.504 -0.248)
			(end -0.494 -0.248)
			(stroke
				(width 0.15)
				(type solid)
			)
			(layer "B.Fab")
		)
		(fp_line
			(start -0.494 0.25)
			(end 0.504 0.25)
			(stroke
				(width 0.15)
				(type solid)
			)
			(layer "B.Fab")
		)
		(fp_line
			(start -0.494 -0.248)
			(end -0.494 0.25)
			(stroke
				(width 0.15)
				(type solid)
			)
			(layer "B.Fab")
		)
		(fp_text user "Author: Antmicro"
			(at -0.939 -3.399 0)
			(layer "B.Fab")
			(effects
				(font
					(size 0.7 0.7)
					(thickness 0.15)
				)
				(justify left bottom mirror)
			)
		)
		(fp_text user "${REFERENCE}"
			(at -0.939 -4.599 0)
			(layer "B.Fab")
			(effects
				(font
					(size 0.7 0.7)
					(thickness 0.15)
				)
				(justify left bottom mirror)
			)
		)
		(fp_text user "License: Apache-2.0"
			(at -0.939 -5.799 0)
			(layer "B.Fab")
			(effects
				(font
					(size 0.7 0.7)
					(thickness 0.15)
				)
				(justify left bottom mirror)
			)
		)
		(pad "1" smd roundrect
			(at -0.48 0 180)
			(size 0.59 0.64)
			(layers "B.Cu" "B.Mask" "B.Paste")
			(roundrect_rratio 0.25)
			(net 23 "GND")
			(pintype "passive")
		)
		(pad "2" smd roundrect
			(at 0.48 0 180)
			(size 0.59 0.64)
			(layers "B.Cu" "B.Mask" "B.Paste")
			(roundrect_rratio 0.25)
			(net 134 "/2xRJ45/P1_CT")
			(pintype "passive")
		)
	)
	(footprint "antmicro-footprints:R_0402_1005Metric"
		(layer "B.Cu")
		(at 134.850002 131.099998 -90)
		(descr "Resistor SMD 0402")
		(tags "resistor SMD 0402")
		(property "Reference" "R25"
			(at -8.35 -19.525001 90)
			(layer "B.SilkS")
			(effects
				(font
					(size 0.7 0.7)
					(thickness 0.15)
				)
				(justify mirror)
			)
		)
		(property "Value" "R_0R_0402"
			(at -1.011843 -1.772047 90)
			(layer "B.Fab")
			(effects
				(font
					(size 0.7 0.7)
					(thickness 0.15)
				)
				(justify left bottom mirror)
			)
		)
		(property "Datasheet" "https://industrial.panasonic.com/cdbs/www-data/pdf/RDA0000/AOA0000C301.pdf"
			(at 0 0 90)
			(layer "B.Fab")
			(hide yes)
			(effects
				(font
					(size 1.27 1.27)
					(thickness 0.15)
				)
				(justify mirror)
			)
		)
		(property "Description" "SMD Chip Resistor, Jumper, 0 ohm, 100 mW, 0402 [1005 Metric], Thick Film, General Purpose"
			(at 0 0 90)
			(layer "B.Fab")
			(hide yes)
			(effects
				(font
					(size 1.27 1.27)
					(thickness 0.15)
				)
				(justify mirror)
			)
		)
		(property "MPN" "ERJ2GE0R00X"
			(at 0 0 270)
			(unlocked yes)
			(layer "B.Fab")
			(hide yes)
			(effects
				(font
					(size 1 1)
					(thickness 0.15)
				)
				(justify mirror)
			)
		)
		(property "Manufacturer" "Panasonic"
			(at 0 0 270)
			(unlocked yes)
			(layer "B.Fab")
			(hide yes)
			(effects
				(font
					(size 1 1)
					(thickness 0.15)
				)
				(justify mirror)
			)
		)
		(property "License" "Apache-2.0"
			(at 0 0 270)
			(unlocked yes)
			(layer "B.Fab")
			(hide yes)
			(effects
				(font
					(size 1 1)
					(thickness 0.15)
				)
				(justify mirror)
			)
		)
		(property "Val" "0R"
			(at 0 0 270)
			(unlocked yes)
			(layer "B.Fab")
			(hide yes)
			(effects
				(font
					(size 1 1)
					(thickness 0.15)
				)
				(justify mirror)
			)
		)
		(property "Tolerance" "~"
			(at 0 0 270)
			(unlocked yes)
			(layer "B.Fab")
			(hide yes)
			(effects
				(font
					(size 1 1)
					(thickness 0.15)
				)
				(justify mirror)
			)
		)
		(property "Current" "1A"
			(at 0 0 270)
			(unlocked yes)
			(layer "B.Fab")
			(hide yes)
			(effects
				(font
					(size 1 1)
					(thickness 0.15)
				)
				(justify mirror)
			)
		)
		(property "Author" "Antmicro"
			(at 0 0 270)
			(unlocked yes)
			(layer "B.Fab")
			(hide yes)
			(effects
				(font
					(size 1 1)
					(thickness 0.15)
				)
				(justify mirror)
			)
		)
		(sheetname "/PD and TB DC-DC/")
		(sheetfile "PD_and_TB_DC_DC.kicad_sch")
		(attr smd)
		(fp_rect
			(start -0.925 0.47)
			(end 0.925 -0.47)
			(stroke
				(width 0.05)
				(type default)
			)
			(fill no)
			(layer "B.CrtYd")
		)
		(fp_rect
			(start -0.5 0.25)
			(end 0.5 -0.25)
			(stroke
				(width 0.15)
				(type solid)
			)
			(fill no)
			(layer "B.Fab")
		)
		(fp_text user "${REFERENCE}"
			(at -0.95 -3.168 90)
			(layer "B.Fab")
			(effects
				(font
					(size 0.7 0.7)
					(thickness 0.15)
				)
				(justify left bottom mirror)
			)
		)
		(fp_text user "License: Apache-2.0"
			(at -0.95 -5.169 90)
			(layer "B.Fab")
			(effects
				(font
					(size 0.7 0.7)
					(thickness 0.15)
				)
				(justify left bottom mirror)
			)
		)
		(fp_text user "Author: Antmicro"
			(at -0.95 -4.169 90)
			(layer "B.Fab")
			(effects
				(font
					(size 0.7 0.7)
					(thickness 0.15)
				)
				(justify left bottom mirror)
			)
		)
		(pad "1" smd roundrect
			(at -0.48 0 270)
			(size 0.59 0.64)
			(layers "B.Cu" "B.Mask" "B.Paste")
			(roundrect_rratio 0.25)
			(net 208 "Net-(U3-I2C_ADDR)")
			(pintype "passive")
		)
		(pad "2" smd roundrect
			(at 0.48 0 270)
			(size 0.59 0.64)
			(layers "B.Cu" "B.Mask" "B.Paste")
			(roundrect_rratio 0.25)
			(net 23 "GND")
			(pintype "passive")
		)
	)
	(footprint "antmicro-footprints:C_0402_1005Metric"
		(layer "B.Cu")
		(at 153.031866 81.260117 180)
		(descr "Capacitor SMD 0402")
		(tags "capacitor SMD 0402")
		(property "Reference" "C229"
			(at -21.168135 -9.464883 0)
			(layer "B.SilkS")
			(effects
				(font
					(size 0.7 0.7)
					(thickness 0.15)
				)
				(justify mirror)
			)
		)
		(property "Value" "C_1u_25V_0402"
			(at -1.022927 -2.155213 0)
			(layer "B.Fab")
			(effects
				(font
					(size 0.7 0.7)
					(thickness 0.15)
				)
				(justify left bottom mirror)
			)
		)
		(property "Datasheet" "https://www.murata.com/products/productdetail?partno=GRM155R61E105KE11%23"
			(at 0 0 0)
			(layer "B.Fab")
			(hide yes)
			(effects
				(font
					(size 1.27 1.27)
					(thickness 0.15)
				)
				(justify mirror)
			)
		)
		(property "Description" "SMD Multilayer Ceramic Capacitor, 1 µF, 25 V, 0402 [1005 Metric], ± 10%, X5R, GRM Series"
			(at 0 0 0)
			(layer "B.Fab")
			(hide yes)
			(effects
				(font
					(size 1.27 1.27)
					(thickness 0.15)
				)
				(justify mirror)
			)
		)
		(property "MPN" "GRM155R61E105KE11J"
			(at 0 0 180)
			(unlocked yes)
			(layer "B.Fab")
			(hide yes)
			(effects
				(font
					(size 1 1)
					(thickness 0.15)
				)
				(justify mirror)
			)
		)
		(property "Manufacturer" "Murata"
			(at 0 0 180)
			(unlocked yes)
			(layer "B.Fab")
			(hide yes)
			(effects
				(font
					(size 1 1)
					(thickness 0.15)
				)
				(justify mirror)
			)
		)
		(property "License" "Apache-2.0"
			(at 0 0 180)
			(unlocked yes)
			(layer "B.Fab")
			(hide yes)
			(effects
				(font
					(size 1 1)
					(thickness 0.15)
				)
				(justify mirror)
			)
		)
		(property "Author" "Antmicro"
			(at 0 0 180)
			(unlocked yes)
			(layer "B.Fab")
			(hide yes)
			(effects
				(font
					(size 1 1)
					(thickness 0.15)
				)
				(justify mirror)
			)
		)
		(property "Val" "1u"
			(at 0 0 180)
			(unlocked yes)
			(layer "B.Fab")
			(hide yes)
			(effects
				(font
					(size 1 1)
					(thickness 0.15)
				)
				(justify mirror)
			)
		)
		(property "Voltage" "25V"
			(at 0 0 180)
			(unlocked yes)
			(layer "B.Fab")
			(hide yes)
			(effects
				(font
					(size 1 1)
					(thickness 0.15)
				)
				(justify mirror)
			)
		)
		(property "Dielectric" "X5R"
			(at 0 0 180)
			(unlocked yes)
			(layer "B.Fab")
			(hide yes)
			(effects
				(font
					(size 1 1)
					(thickness 0.15)
				)
				(justify mirror)
			)
		)
		(sheetname "/X710-AT2 power/")
		(sheetfile "x710-at2-power.kicad_sch")
		(attr smd)
		(fp_rect
			(start -0.925 0.47)
			(end 0.925 -0.47)
			(stroke
				(width 0.05)
				(type default)
			)
			(fill no)
			(layer "B.CrtYd")
		)
		(fp_line
			(start 0.504 0.25)
			(end 0.504 -0.248)
			(stroke
				(width 0.15)
				(type solid)
			)
			(layer "B.Fab")
		)
		(fp_line
			(start 0.504 -0.248)
			(end -0.494 -0.248)
			(stroke
				(width 0.15)
				(type solid)
			)
			(layer "B.Fab")
		)
		(fp_line
			(start -0.494 0.25)
			(end 0.504 0.25)
			(stroke
				(width 0.15)
				(type solid)
			)
			(layer "B.Fab")
		)
		(fp_line
			(start -0.494 -0.248)
			(end -0.494 0.25)
			(stroke
				(width 0.15)
				(type solid)
			)
			(layer "B.Fab")
		)
		(fp_text user "${REFERENCE}"
			(at -0.939 -4.599 0)
			(layer "B.Fab")
			(effects
				(font
					(size 0.7 0.7)
					(thickness 0.15)
				)
				(justify left bottom mirror)
			)
		)
		(fp_text user "License: Apache-2.0"
			(at -0.939 -5.799 0)
			(layer "B.Fab")
			(effects
				(font
					(size 0.7 0.7)
					(thickness 0.15)
				)
				(justify left bottom mirror)
			)
		)
		(fp_text user "Author: Antmicro"
			(at -0.939 -3.399 0)
			(layer "B.Fab")
			(effects
				(font
					(size 0.7 0.7)
					(thickness 0.15)
				)
				(justify left bottom mirror)
			)
		)
		(pad "1" smd roundrect
			(at -0.48 0 180)
			(size 0.59 0.64)
			(layers "B.Cu" "B.Mask" "B.Paste")
			(roundrect_rratio 0.25)
			(net 23 "GND")
			(pintype "passive")
		)
		(pad "2" smd roundrect
			(at 0.48 0 180)
			(size 0.59 0.64)
			(layers "B.Cu" "B.Mask" "B.Paste")
			(roundrect_rratio 0.25)
			(net 9 "VCCD")
			(pintype "passive")
		)
	)
	(footprint "antmicro-footprints:R_0402_1005Metric"
		(layer "B.Cu")
		(at 154.131866 70.035118 90)
		(descr "Resistor SMD 0402")
		(tags "resistor SMD 0402")
		(property "Reference" "R187"
			(at -9.464883 19.468134 270)
			(layer "B.SilkS")
			(effects
				(font
					(size 0.7 0.7)
					(thickness 0.15)
				)
				(justify mirror)
			)
		)
		(property "Value" "R_3k3_0402"
			(at -1.011843 -1.772047 270)
			(layer "B.Fab")
			(effects
				(font
					(size 0.7 0.7)
					(thickness 0.15)
				)
				(justify left bottom mirror)
			)
		)
		(property "Datasheet" "https://www.bourns.com/docs/product-datasheets/cr.pdf"
			(at 0 0 270)
			(layer "B.Fab")
			(hide yes)
			(effects
				(font
					(size 1.27 1.27)
					(thickness 0.15)
				)
				(justify mirror)
			)
		)
		(property "Description" "SMD Chip Resistor, 3.3 kohm, ± 1%, 63 mW, 0402 [1005 Metric], Thick Film, General Purpose"
			(at 0 0 270)
			(layer "B.Fab")
			(hide yes)
			(effects
				(font
					(size 1.27 1.27)
					(thickness 0.15)
				)
				(justify mirror)
			)
		)
		(property "MPN" "CR0402-FX-3301GLF"
			(at 0 0 90)
			(unlocked yes)
			(layer "B.Fab")
			(hide yes)
			(effects
				(font
					(size 1 1)
					(thickness 0.15)
				)
				(justify mirror)
			)
		)
		(property "Manufacturer" "Bourns"
			(at 0 0 90)
			(unlocked yes)
			(layer "B.Fab")
			(hide yes)
			(effects
				(font
					(size 1 1)
					(thickness 0.15)
				)
				(justify mirror)
			)
		)
		(property "License" "Apache-2.0"
			(at 0 0 90)
			(unlocked yes)
			(layer "B.Fab")
			(hide yes)
			(effects
				(font
					(size 1 1)
					(thickness 0.15)
				)
				(justify mirror)
			)
		)
		(property "Author" "Antmicro"
			(at 0 0 90)
			(unlocked yes)
			(layer "B.Fab")
			(hide yes)
			(effects
				(font
					(size 1 1)
					(thickness 0.15)
				)
				(justify mirror)
			)
		)
		(property "Val" "3k3"
			(at 0 0 90)
			(unlocked yes)
			(layer "B.Fab")
			(hide yes)
			(effects
				(font
					(size 1 1)
					(thickness 0.15)
				)
				(justify mirror)
			)
		)
		(property "Tolerance" "1%"
			(at 0 0 90)
			(unlocked yes)
			(layer "B.Fab")
			(hide yes)
			(effects
				(font
					(size 1 1)
					(thickness 0.15)
				)
				(justify mirror)
			)
		)
		(sheetname "/X710-AT2 10GbE/")
		(sheetfile "x710-at2-10gbe.kicad_sch")
		(attr smd)
		(fp_rect
			(start -0.925 0.47)
			(end 0.925 -0.47)
			(stroke
				(width 0.05)
				(type default)
			)
			(fill no)
			(layer "B.CrtYd")
		)
		(fp_rect
			(start -0.5 0.25)
			(end 0.5 -0.25)
			(stroke
				(width 0.15)
				(type solid)
			)
			(fill no)
			(layer "B.Fab")
		)
		(fp_text user "${REFERENCE}"
			(at -0.95 -3.168 270)
			(layer "B.Fab")
			(effects
				(font
					(size 0.7 0.7)
					(thickness 0.15)
				)
				(justify left bottom mirror)
			)
		)
		(fp_text user "License: Apache-2.0"
			(at -0.95 -5.169 270)
			(layer "B.Fab")
			(effects
				(font
					(size 0.7 0.7)
					(thickness 0.15)
				)
				(justify left bottom mirror)
			)
		)
		(fp_text user "Author: Antmicro"
			(at -0.95 -4.169 270)
			(layer "B.Fab")
			(effects
				(font
					(size 0.7 0.7)
					(thickness 0.15)
				)
				(justify left bottom mirror)
			)
		)
		(pad "1" smd roundrect
			(at -0.48 0 90)
			(size 0.59 0.64)
			(layers "B.Cu" "B.Mask" "B.Paste")
			(roundrect_rratio 0.25)
			(net 70 "/X710-AT2 10GbE/MDC3_SCL3")
			(pintype "passive")
		)
		(pad "2" smd roundrect
			(at 0.48 0 90)
			(size 0.59 0.64)
			(layers "B.Cu" "B.Mask" "B.Paste")
			(roundrect_rratio 0.25)
			(net 7 "+3V3")
			(pintype "passive")
		)
	)
	(footprint "antmicro-footprints:R_0402_1005Metric"
		(layer "B.Cu")
		(at 137.5 126.6)
		(descr "Resistor SMD 0402")
		(tags "resistor SMD 0402")
		(property "Reference" "R50"
			(at 19.525001 -7.450001 180)
			(layer "B.SilkS")
			(effects
				(font
					(size 0.7 0.7)
					(thickness 0.15)
				)
				(justify mirror)
			)
		)
		(property "Value" "R_100k_0402"
			(at -1.011843 -1.772047 180)
			(layer "B.Fab")
			(effects
				(font
					(size 0.7 0.7)
					(thickness 0.15)
				)
				(justify left bottom mirror)
			)
		)
		(property "Datasheet" "https://www.bourns.com/docs/product-datasheets/cr.pdf"
			(at 0 0 180)
			(layer "B.Fab")
			(hide yes)
			(effects
				(font
					(size 1.27 1.27)
					(thickness 0.15)
				)
				(justify mirror)
			)
		)
		(property "Description" "SMD Chip Resistor, 100 kohm, ± 1%, 62.5 mW, 0402 [1005 Metric], Thick Film, General Purpose"
			(at 0 0 180)
			(layer "B.Fab")
			(hide yes)
			(effects
				(font
					(size 1.27 1.27)
					(thickness 0.15)
				)
				(justify mirror)
			)
		)
		(property "MPN" "CR0402-FX-1003GLF"
			(at 0 0 0)
			(unlocked yes)
			(layer "B.Fab")
			(hide yes)
			(effects
				(font
					(size 1 1)
					(thickness 0.15)
				)
				(justify mirror)
			)
		)
		(property "Manufacturer" "Bourns"
			(at 0 0 0)
			(unlocked yes)
			(layer "B.Fab")
			(hide yes)
			(effects
				(font
					(size 1 1)
					(thickness 0.15)
				)
				(justify mirror)
			)
		)
		(property "License" "Apache-2.0"
			(at 0 0 0)
			(unlocked yes)
			(layer "B.Fab")
			(hide yes)
			(effects
				(font
					(size 1 1)
					(thickness 0.15)
				)
				(justify mirror)
			)
		)
		(property "Val" "100k"
			(at 0 0 0)
			(unlocked yes)
			(layer "B.Fab")
			(hide yes)
			(effects
				(font
					(size 1 1)
					(thickness 0.15)
				)
				(justify mirror)
			)
		)
		(property "Tolerance" "1%"
			(at 0 0 0)
			(unlocked yes)
			(layer "B.Fab")
			(hide yes)
			(effects
				(font
					(size 1 1)
					(thickness 0.15)
				)
				(justify mirror)
			)
		)
		(property "Author" "Antmicro"
			(at 0 0 0)
			(unlocked yes)
			(layer "B.Fab")
			(hide yes)
			(effects
				(font
					(size 1 1)
					(thickness 0.15)
				)
				(justify mirror)
			)
		)
		(sheetname "/TB Controller/")
		(sheetfile "tb.kicad_sch")
		(attr smd)
		(fp_rect
			(start -0.925 0.47)
			(end 0.925 -0.47)
			(stroke
				(width 0.05)
				(type default)
			)
			(fill no)
			(layer "B.CrtYd")
		)
		(fp_rect
			(start -0.5 0.25)
			(end 0.5 -0.25)
			(stroke
				(width 0.15)
				(type solid)
			)
			(fill no)
			(layer "B.Fab")
		)
		(fp_text user "Author: Antmicro"
			(at -0.95 -4.169 180)
			(layer "B.Fab")
			(effects
				(font
					(size 0.7 0.7)
					(thickness 0.15)
				)
				(justify left bottom mirror)
			)
		)
		(fp_text user "${REFERENCE}"
			(at -0.95 -3.168 180)
			(layer "B.Fab")
			(effects
				(font
					(size 0.7 0.7)
					(thickness 0.15)
				)
				(justify left bottom mirror)
			)
		)
		(fp_text user "License: Apache-2.0"
			(at -0.95 -5.169 180)
			(layer "B.Fab")
			(effects
				(font
					(size 0.7 0.7)
					(thickness 0.15)
				)
				(justify left bottom mirror)
			)
		)
		(pad "1" smd roundrect
			(at -0.48 0)
			(size 0.59 0.64)
			(layers "B.Cu" "B.Mask" "B.Paste")
			(roundrect_rratio 0.25)
			(net 193 "Net-(U4C-POC_GPIO_2)")
			(pintype "passive")
		)
		(pad "2" smd roundrect
			(at 0.48 0)
			(size 0.59 0.64)
			(layers "B.Cu" "B.Mask" "B.Paste")
			(roundrect_rratio 0.25)
			(net 23 "GND")
			(pintype "passive")
		)
	)
)
